# T6G (Grand Teton) — schematic netlist excerpt (pin names and nets, part order shuffled) for the footprints in the layout excerpt that follows; sources: Cadence DE-HDL packaged netlist, KiCad conversion of 04192023_DAF0TMB3IC0_F0TG_MB_C_brd_V02_OCP.brd

R214  Q_RES  33 5% CHIP  pkg 0402LF  page 269 : A = PWRGD_P1V8_AUX ; B = PWRGD_P1V8_AUX_R
R6098  Q_RES  10K 5% EMPTY  pkg 0402LF  page 76 : A = GND ; B = SPI_CPU0_CLK

(kicad_pcb
	(version 20260206)
	(generator "pcbnew")
	(generator_version "10.0")
	(general
		(thickness 1.6)
		(legacy_teardrops no)
	)
	(paper "A4")
	(title_block
		(title "04192023_DAF0TMB3IC0_F0TG_MB_C_brd_V02_OCP.brd")
		(comment 1 "Grand Teton / footprints 4147-4148 of 8354")
	)
	(layers
		(0 "F.Cu" signal "TOP")
		(4 "In1.Cu" signal "GND")
		(6 "In2.Cu" signal "IN1")
		(8 "In3.Cu" signal "GND1")
		(10 "In4.Cu" signal "IN2")
		(12 "In5.Cu" signal "GND2")
		(14 "In6.Cu" signal "IN3")
		(16 "In7.Cu" signal "GND3")
		(18 "In8.Cu" signal "VCC")
		(20 "In9.Cu" signal "VCC1")
		(22 "In10.Cu" signal "GND4")
		(24 "In11.Cu" signal "IN4")
		(26 "In12.Cu" signal "GND5")
		(28 "In13.Cu" signal "IN5")
		(30 "In14.Cu" signal "GND6")
		(32 "In15.Cu" signal "IN6")
		(34 "In16.Cu" signal "GND7")
		(2 "B.Cu" signal "BOTTOM")
		(9 "F.Adhes" user "F.Adhesive")
		(11 "B.Adhes" user "B.Adhesive")
		(13 "F.Paste" user "Package Geometry/Pastemask Top")
		(15 "B.Paste" user "Package Geometry/Pastemask Bottom")
		(5 "F.SilkS" user "Ref Des/Silkscreen Top")
		(7 "B.SilkS" user "Ref Des/Silkscreen Bottom")
		(1 "F.Mask" user "Board Geometry/Soldermask Top")
		(3 "B.Mask" user "Board Geometry/Soldermask Bottom")
		(17 "Dwgs.User" user "User.Drawings")
		(19 "Cmts.User" user "User.Comments")
		(21 "Eco1.User" user "User.Eco1")
		(23 "Eco2.User" user "User.Eco2")
		(25 "Edge.Cuts" user "Board Geometry/Outline")
		(27 "Margin" user)
		(31 "F.CrtYd" user "Package Geometry/Place Bound Top")
		(29 "B.CrtYd" user "Package Geometry/Place Bound Bottom")
		(35 "F.Fab" user "Ref Des/Assembly Top")
		(33 "B.Fab" user "Ref Des/Assembly Bottom")
	)
	(footprint ""
		(layer "F.Cu")
		(at 264.478516 -132.352796 180)
		(property "Reference" "R6098"
			(at 0 0 180)
			(layer "F.SilkS")
			(hide yes)
			(effects
				(font
					(size 1.27 1.27)
				)
			)
		)
		(property "Value" ""
			(at 0 0 180)
			(layer "F.Fab")
			(effects
				(font
					(size 1.27 1.27)
				)
			)
		)
		(duplicate_pad_numbers_are_jumpers no)
		(fp_line
			(start 0.7874 0.4064)
			(end -0.7874 0.4064)
			(stroke
				(width 0.1524)
				(type default)
			)
			(layer "F.SilkS")
		)
		(fp_line
			(start 0.7874 -0.4064)
			(end 0.7874 0.4064)
			(stroke
				(width 0.1524)
				(type default)
			)
			(layer "F.SilkS")
		)
		(fp_line
			(start -0.7874 0.4064)
			(end -0.7874 -0.4064)
			(stroke
				(width 0.1524)
				(type default)
			)
			(layer "F.SilkS")
		)
		(fp_line
			(start -0.7874 -0.4064)
			(end 0.7874 -0.4064)
			(stroke
				(width 0.1524)
				(type default)
			)
			(layer "F.SilkS")
		)
		(fp_line
			(start 0.67945 0.3048)
			(end 0.120396 0.3048)
			(stroke
				(width 0.1)
				(type default)
			)
			(layer "F.Fab")
		)
		(fp_line
			(start 0.67945 -0.3048)
			(end 0.67945 0.3048)
			(stroke
				(width 0.1)
				(type default)
			)
			(layer "F.Fab")
		)
		(fp_line
			(start 0.12065 -0.2794)
			(end 0.12065 -0.3048)
			(stroke
				(width 0.1)
				(type default)
			)
			(layer "F.Fab")
		)
		(fp_line
			(start 0.12065 -0.3048)
			(end 0.67945 -0.3048)
			(stroke
				(width 0.1)
				(type default)
			)
			(layer "F.Fab")
		)
		(fp_line
			(start 0.120396 0.3048)
			(end 0.120396 0.2794)
			(stroke
				(width 0.1)
				(type default)
			)
			(layer "F.Fab")
		)
		(fp_line
			(start 0.120396 0.2794)
			(end -0.12065 0.2794)
			(stroke
				(width 0.1)
				(type default)
			)
			(layer "F.Fab")
		)
		(fp_line
			(start -0.12065 0.3048)
			(end -0.67945 0.3048)
			(stroke
				(width 0.1)
				(type default)
			)
			(layer "F.Fab")
		)
		(fp_line
			(start -0.12065 0.2794)
			(end -0.12065 0.3048)
			(stroke
				(width 0.1)
				(type default)
			)
			(layer "F.Fab")
		)
		(fp_line
			(start -0.12065 -0.2794)
			(end 0.12065 -0.2794)
			(stroke
				(width 0.1)
				(type default)
			)
			(layer "F.Fab")
		)
		(fp_line
			(start -0.12065 -0.305054)
			(end -0.12065 -0.2794)
			(stroke
				(width 0.1)
				(type default)
			)
			(layer "F.Fab")
		)
		(fp_line
			(start -0.67945 0.3048)
			(end -0.67945 -0.305054)
			(stroke
				(width 0.1)
				(type default)
			)
			(layer "F.Fab")
		)
		(fp_line
			(start -0.67945 -0.305054)
			(end -0.12065 -0.305054)
			(stroke
				(width 0.1)
				(type default)
			)
			(layer "F.Fab")
		)
		(pad "1" smd circle
			(at -0.40005 0 180)
			(size 0 0)
			(layers "F.Cu" "F.Mask" "F.Paste")
			(net "GND")
		)
		(pad "2" smd circle
			(at 0.40005 0 180)
			(size 0 0)
			(layers "F.Cu" "F.Mask" "F.Paste")
			(net "SPI_CPU0_CLK")
		)
	)
	(footprint ""
		(layer "F.Cu")
		(at 215.330278 -128.804924)
		(property "Reference" "R214"
			(at 0 0 0)
			(layer "F.SilkS")
			(hide yes)
			(effects
				(font
					(size 1.27 1.27)
				)
			)
		)
		(property "Value" ""
			(at 0 0 0)
			(layer "F.Fab")
			(effects
				(font
					(size 1.27 1.27)
				)
			)
		)
		(duplicate_pad_numbers_are_jumpers no)
		(fp_line
			(start -0.7874 -0.4064)
			(end 0.7874 -0.4064)
			(stroke
				(width 0.1524)
				(type default)
			)
			(layer "F.SilkS")
		)
		(fp_line
			(start -0.7874 0.4064)
			(end -0.7874 -0.4064)
			(stroke
				(width 0.1524)
				(type default)
			)
			(layer "F.SilkS")
		)
		(fp_line
			(start 0.7874 -0.4064)
			(end 0.7874 0.4064)
			(stroke
				(width 0.1524)
				(type default)
			)
			(layer "F.SilkS")
		)
		(fp_line
			(start 0.7874 0.4064)
			(end -0.7874 0.4064)
			(stroke
				(width 0.1524)
				(type default)
			)
			(layer "F.SilkS")
		)
		(fp_line
			(start -0.67945 -0.305054)
			(end -0.12065 -0.305054)
			(stroke
				(width 0.1)
				(type default)
			)
			(layer "F.Fab")
		)
		(fp_line
			(start -0.67945 0.3048)
			(end -0.67945 -0.305054)
			(stroke
				(width 0.1)
				(type default)
			)
			(layer "F.Fab")
		)
		(fp_line
			(start -0.12065 -0.305054)
			(end -0.12065 -0.2794)
			(stroke
				(width 0.1)
				(type default)
			)
			(layer "F.Fab")
		)
		(fp_line
			(start -0.12065 -0.2794)
			(end 0.12065 -0.2794)
			(stroke
				(width 0.1)
				(type default)
			)
			(layer "F.Fab")
		)
		(fp_line
			(start -0.12065 0.2794)
			(end -0.12065 0.3048)
			(stroke
				(width 0.1)
				(type default)
			)
			(layer "F.Fab")
		)
		(fp_line
			(start -0.12065 0.3048)
			(end -0.67945 0.3048)
			(stroke
				(width 0.1)
				(type default)
			)
			(layer "F.Fab")
		)
		(fp_line
			(start 0.120396 0.2794)
			(end -0.12065 0.2794)
			(stroke
				(width 0.1)
				(type default)
			)
			(layer "F.Fab")
		)
		(fp_line
			(start 0.120396 0.3048)
			(end 0.120396 0.2794)
			(stroke
				(width 0.1)
				(type default)
			)
			(layer "F.Fab")
		)
		(fp_line
			(start 0.12065 -0.3048)
			(end 0.67945 -0.3048)
			(stroke
				(width 0.1)
				(type default)
			)
			(layer "F.Fab")
		)
		(fp_line
			(start 0.12065 -0.2794)
			(end 0.12065 -0.3048)
			(stroke
				(width 0.1)
				(type default)
			)
			(layer "F.Fab")
		)
		(fp_line
			(start 0.67945 -0.3048)
			(end 0.67945 0.3048)
			(stroke
				(width 0.1)
				(type default)
			)
			(layer "F.Fab")
		)
		(fp_line
			(start 0.67945 0.3048)
			(end 0.120396 0.3048)
			(stroke
				(width 0.1)
				(type default)
			)
			(layer "F.Fab")
		)
		(pad "1" smd circle
			(at -0.40005 0)
			(size 0 0)
			(layers "F.Cu" "F.Mask" "F.Paste")
			(net "PWRGD_P1V8_AUX")
		)
		(pad "2" smd circle
			(at 0.40005 0)
			(size 0 0)
			(layers "F.Cu" "F.Mask" "F.Paste")
			(net "PWRGD_P1V8_AUX_R")
		)
	)
)
